# S9S_MB_2U (Grand Teton) — schematic netlist excerpt (pin names and nets, part order shuffled) for the footprints in the layout excerpt that follows; sources: Cadence DE-HDL packaged netlist, KiCad conversion of 03242023_DA0F0TMBIJ0_F0T_Motherboard_J_brd_V01_OCP.brd

R3072  Q_RES  130 1% CHIP  pkg 0402LF  page 252 : A = LED_PWRGD_P1V05_PCH_AUX ; B = P3V3_AUX
R3784  Q_RES  0 5% EMPTY  pkg 0402LF  page 156 : A = P12V_OCP_UV_1_R ; B = P12V_OCP_UV_1

(kicad_pcb
	(version 20260206)
	(generator "pcbnew")
	(generator_version "10.0")
	(general
		(thickness 1.6)
		(legacy_teardrops no)
	)
	(paper "A4")
	(title_block
		(title "03242023_DA0F0TMBIJ0_F0T_Motherboard_J_brd_V01_OCP.brd")
		(comment 1 "Grand Teton / footprints 3457-3458 of 6105")
	)
	(layers
		(0 "F.Cu" signal "TOP")
		(4 "In1.Cu" signal "GND")
		(6 "In2.Cu" signal "IN1")
		(8 "In3.Cu" signal "GND1")
		(10 "In4.Cu" signal "IN2")
		(12 "In5.Cu" signal "GND2")
		(14 "In6.Cu" signal "IN3")
		(16 "In7.Cu" signal "GND3")
		(18 "In8.Cu" signal "VCC")
		(20 "In9.Cu" signal "VCC1")
		(22 "In10.Cu" signal "GND4")
		(24 "In11.Cu" signal "IN4")
		(26 "In12.Cu" signal "GND5")
		(28 "In13.Cu" signal "IN5")
		(30 "In14.Cu" signal "GND6")
		(32 "In15.Cu" signal "IN6")
		(34 "In16.Cu" signal "GND7")
		(2 "B.Cu" signal "BOTTOM")
		(9 "F.Adhes" user "F.Adhesive")
		(11 "B.Adhes" user "B.Adhesive")
		(13 "F.Paste" user "Package Geometry/Pastemask Top")
		(15 "B.Paste" user "Package Geometry/Pastemask Bottom")
		(5 "F.SilkS" user "Ref Des/Silkscreen Top")
		(7 "B.SilkS" user "Ref Des/Silkscreen Bottom")
		(1 "F.Mask" user "Board Geometry/Soldermask Top")
		(3 "B.Mask" user "Board Geometry/Soldermask Bottom")
		(17 "Dwgs.User" user "User.Drawings")
		(19 "Cmts.User" user "User.Comments")
		(21 "Eco1.User" user "User.Eco1")
		(23 "Eco2.User" user "User.Eco2")
		(25 "Edge.Cuts" user "Board Geometry/Outline")
		(27 "Margin" user)
		(31 "F.CrtYd" user "Package Geometry/Place Bound Top")
		(29 "B.CrtYd" user "Package Geometry/Place Bound Bottom")
		(35 "F.Fab" user "Ref Des/Assembly Top")
		(33 "B.Fab" user "Ref Des/Assembly Bottom")
	)
	(footprint ""
		(layer "F.Cu")
		(at 105.973372 -74.993246 -90)
		(property "Reference" "R3072"
			(at 0 0 270)
			(layer "F.SilkS")
			(hide yes)
			(effects
				(font
					(size 1.27 1.27)
				)
			)
		)
		(property "Value" ""
			(at 0 0 270)
			(layer "F.Fab")
			(effects
				(font
					(size 1.27 1.27)
				)
			)
		)
		(duplicate_pad_numbers_are_jumpers no)
		(fp_line
			(start -0.7874 0.4064)
			(end -0.7874 -0.4064)
			(stroke
				(width 0.1524)
				(type default)
			)
			(layer "F.SilkS")
		)
		(fp_line
			(start 0.7874 0.4064)
			(end -0.7874 0.4064)
			(stroke
				(width 0.1524)
				(type default)
			)
			(layer "F.SilkS")
		)
		(fp_line
			(start -0.7874 -0.4064)
			(end 0.7874 -0.4064)
			(stroke
				(width 0.1524)
				(type default)
			)
			(layer "F.SilkS")
		)
		(fp_line
			(start 0.7874 -0.4064)
			(end 0.7874 0.4064)
			(stroke
				(width 0.1524)
				(type default)
			)
			(layer "F.SilkS")
		)
		(fp_line
			(start -0.67945 0.3048)
			(end -0.67945 -0.305054)
			(stroke
				(width 0.1)
				(type default)
			)
			(layer "F.Fab")
		)
		(fp_line
			(start -0.12065 0.3048)
			(end -0.67945 0.3048)
			(stroke
				(width 0.1)
				(type default)
			)
			(layer "F.Fab")
		)
		(fp_line
			(start 0.120396 0.3048)
			(end 0.120396 0.2794)
			(stroke
				(width 0.1)
				(type default)
			)
			(layer "F.Fab")
		)
		(fp_line
			(start 0.67945 0.3048)
			(end 0.120396 0.3048)
			(stroke
				(width 0.1)
				(type default)
			)
			(layer "F.Fab")
		)
		(fp_line
			(start -0.12065 0.2794)
			(end -0.12065 0.3048)
			(stroke
				(width 0.1)
				(type default)
			)
			(layer "F.Fab")
		)
		(fp_line
			(start 0.120396 0.2794)
			(end -0.12065 0.2794)
			(stroke
				(width 0.1)
				(type default)
			)
			(layer "F.Fab")
		)
		(fp_line
			(start -0.12065 -0.2794)
			(end 0.12065 -0.2794)
			(stroke
				(width 0.1)
				(type default)
			)
			(layer "F.Fab")
		)
		(fp_line
			(start 0.12065 -0.2794)
			(end 0.12065 -0.3048)
			(stroke
				(width 0.1)
				(type default)
			)
			(layer "F.Fab")
		)
		(fp_line
			(start 0.12065 -0.3048)
			(end 0.67945 -0.3048)
			(stroke
				(width 0.1)
				(type default)
			)
			(layer "F.Fab")
		)
		(fp_line
			(start 0.67945 -0.3048)
			(end 0.67945 0.3048)
			(stroke
				(width 0.1)
				(type default)
			)
			(layer "F.Fab")
		)
		(fp_line
			(start -0.67945 -0.305054)
			(end -0.12065 -0.305054)
			(stroke
				(width 0.1)
				(type default)
			)
			(layer "F.Fab")
		)
		(fp_line
			(start -0.12065 -0.305054)
			(end -0.12065 -0.2794)
			(stroke
				(width 0.1)
				(type default)
			)
			(layer "F.Fab")
		)
		(pad "1" smd circle
			(at -0.40005 0 270)
			(size 0 0)
			(layers "F.Cu" "F.Mask" "F.Paste")
			(net "LED_PWRGD_P1V05_PCH_AUX")
		)
		(pad "2" smd circle
			(at 0.40005 0 270)
			(size 0 0)
			(layers "F.Cu" "F.Mask" "F.Paste")
			(net "P3V3_AUX")
		)
	)
	(footprint ""
		(layer "F.Cu")
		(at 460.74457 -36.70808 -90)
		(property "Reference" "R3784"
			(at 0 0 270)
			(layer "F.SilkS")
			(hide yes)
			(effects
				(font
					(size 1.27 1.27)
				)
			)
		)
		(property "Value" ""
			(at 0 0 270)
			(layer "F.Fab")
			(effects
				(font
					(size 1.27 1.27)
				)
			)
		)
		(duplicate_pad_numbers_are_jumpers no)
		(fp_line
			(start -0.7874 0.4064)
			(end -0.7874 -0.4064)
			(stroke
				(width 0.1524)
				(type default)
			)
			(layer "F.SilkS")
		)
		(fp_line
			(start 0.7874 0.4064)
			(end -0.7874 0.4064)
			(stroke
				(width 0.1524)
				(type default)
			)
			(layer "F.SilkS")
		)
		(fp_line
			(start -0.7874 -0.4064)
			(end 0.7874 -0.4064)
			(stroke
				(width 0.1524)
				(type default)
			)
			(layer "F.SilkS")
		)
		(fp_line
			(start 0.7874 -0.4064)
			(end 0.7874 0.4064)
			(stroke
				(width 0.1524)
				(type default)
			)
			(layer "F.SilkS")
		)
		(fp_line
			(start -0.67945 0.3048)
			(end -0.67945 -0.305054)
			(stroke
				(width 0.1)
				(type default)
			)
			(layer "F.Fab")
		)
		(fp_line
			(start -0.12065 0.3048)
			(end -0.67945 0.3048)
			(stroke
				(width 0.1)
				(type default)
			)
			(layer "F.Fab")
		)
		(fp_line
			(start 0.120396 0.3048)
			(end 0.120396 0.2794)
			(stroke
				(width 0.1)
				(type default)
			)
			(layer "F.Fab")
		)
		(fp_line
			(start 0.67945 0.3048)
			(end 0.120396 0.3048)
			(stroke
				(width 0.1)
				(type default)
			)
			(layer "F.Fab")
		)
		(fp_line
			(start -0.12065 0.2794)
			(end -0.12065 0.3048)
			(stroke
				(width 0.1)
				(type default)
			)
			(layer "F.Fab")
		)
		(fp_line
			(start 0.120396 0.2794)
			(end -0.12065 0.2794)
			(stroke
				(width 0.1)
				(type default)
			)
			(layer "F.Fab")
		)
		(fp_line
			(start -0.12065 -0.2794)
			(end 0.12065 -0.2794)
			(stroke
				(width 0.1)
				(type default)
			)
			(layer "F.Fab")
		)
		(fp_line
			(start 0.12065 -0.2794)
			(end 0.12065 -0.3048)
			(stroke
				(width 0.1)
				(type default)
			)
			(layer "F.Fab")
		)
		(fp_line
			(start 0.12065 -0.3048)
			(end 0.67945 -0.3048)
			(stroke
				(width 0.1)
				(type default)
			)
			(layer "F.Fab")
		)
		(fp_line
			(start 0.67945 -0.3048)
			(end 0.67945 0.3048)
			(stroke
				(width 0.1)
				(type default)
			)
			(layer "F.Fab")
		)
		(fp_line
			(start -0.67945 -0.305054)
			(end -0.12065 -0.305054)
			(stroke
				(width 0.1)
				(type default)
			)
			(layer "F.Fab")
		)
		(fp_line
			(start -0.12065 -0.305054)
			(end -0.12065 -0.2794)
			(stroke
				(width 0.1)
				(type default)
			)
			(layer "F.Fab")
		)
		(pad "1" smd circle
			(at -0.40005 0 270)
			(size 0 0)
			(layers "F.Cu" "F.Mask" "F.Paste")
			(net "P12V_OCP_UV_1_R")
		)
		(pad "2" smd circle
			(at 0.40005 0 270)
			(size 0 0)
			(layers "F.Cu" "F.Mask" "F.Paste")
			(net "P12V_OCP_UV_1")
		)
	)
)
